(kicad_pcb
	(version 20260206)
	(generator "pcbnew")
	(generator_version "10.0")
	(general
		(thickness 1.6)
		(legacy_teardrops no)
	)
	(paper "A4")
	(title_block
		(title "Wiwynn_Tioga_Pass_MB.brd")
		(comment 1 "Tioga Pass / footprints 2461-2467 of 4770")
	)
	(layers
		(0 "F.Cu" signal "TOP")
		(4 "In1.Cu" signal "L2GND")
		(6 "In2.Cu" signal "L3")
		(8 "In3.Cu" signal "L4GND")
		(10 "In4.Cu" signal "L5")
		(12 "In5.Cu" signal "L6GND")
		(14 "In6.Cu" signal "L7VCC")
		(16 "In7.Cu" signal "L8VCC")
		(18 "In8.Cu" signal "L9GND")
		(20 "In9.Cu" signal "L10")
		(22 "In10.Cu" signal "L11GND")
		(24 "In11.Cu" signal "L12")
		(26 "In12.Cu" signal "L13GND")
		(2 "B.Cu" signal "BOTTOM")
		(9 "F.Adhes" user "F.Adhesive")
		(11 "B.Adhes" user "B.Adhesive")
		(13 "F.Paste" user "Package Geometry/Pastemask Top")
		(15 "B.Paste" user "Package Geometry/Pastemask Bottom")
		(5 "F.SilkS" user "Ref Des/Silkscreen Top")
		(7 "B.SilkS" user "Ref Des/Silkscreen Bottom")
		(1 "F.Mask" user "Board Geometry/Soldermask Top")
		(3 "B.Mask" user "Board Geometry/Soldermask Bottom")
		(17 "Dwgs.User" user "User.Drawings")
		(19 "Cmts.User" user "User.Comments")
		(21 "Eco1.User" user "User.Eco1")
		(23 "Eco2.User" user "User.Eco2")
		(25 "Edge.Cuts" user "Board Geometry/Outline")
		(27 "Margin" user)
		(31 "F.CrtYd" user "Package Geometry/Place Bound Top")
		(29 "B.CrtYd" user "Package Geometry/Place Bound Bottom")
		(35 "F.Fab" user "Ref Des/Assembly Top")
		(33 "B.Fab" user "Ref Des/Assembly Bottom")
	)
	(footprint ""
		(layer "B.Cu")
		(at 408.333956 -114.984784 180)
		(property "Reference" "C2M11"
			(at 0 0 0)
			(layer "B.SilkS")
			(hide yes)
			(effects
				(font
					(size 1.27 1.27)
				)
				(justify mirror)
			)
		)
		(property "Value" ""
			(at 0 0 0)
			(layer "B.Fab")
			(effects
				(font
					(size 1.27 1.27)
				)
				(justify mirror)
			)
		)
		(duplicate_pad_numbers_are_jumpers no)
		(fp_poly
			(pts
				(xy 0.7239 -0.2159) (xy -0.7239 -0.2159) (xy -0.7239 1.9939) (xy 0.7239 1.9939)
			)
			(stroke
				(width 0)
				(type default)
			)
			(fill no)
			(layer "B.CrtYd")
		)
		(fp_line
			(start 0.7239 1.9939)
			(end -0.7239 1.9939)
			(stroke
				(width 0.1)
				(type default)
			)
			(layer "B.Fab")
		)
		(fp_line
			(start 0.7239 -0.2159)
			(end 0.7239 1.9939)
			(stroke
				(width 0.1)
				(type default)
			)
			(layer "B.Fab")
		)
		(fp_line
			(start -0.7239 1.9939)
			(end -0.7239 -0.2159)
			(stroke
				(width 0.1)
				(type default)
			)
			(layer "B.Fab")
		)
		(fp_line
			(start -0.7239 -0.2159)
			(end 0.7239 -0.2159)
			(stroke
				(width 0.1)
				(type default)
			)
			(layer "B.Fab")
		)
		(pad "1" smd rect
			(at 0 0)
			(size 1.27 1.016)
			(layers "B.Cu" "B.Mask" "B.Paste")
			(net "P1V05_PCH_STBY")
		)
		(pad "2" smd rect
			(at 0 1.778)
			(size 1.27 1.016)
			(layers "B.Cu" "B.Mask" "B.Paste")
			(net "GND")
		)
		(zone
			(layer "B.Cu")
			(hatch none 0.5)
			(connect_pads
				(clearance 0)
			)
			(min_thickness 0.25)
			(keepout
				(tracks not_allowed)
				(vias allowed)
				(pads allowed)
				(copperpour not_allowed)
				(footprints allowed)
			)
			(placement
				(enabled no)
				(sheetname "")
			)
			(fill
				(thermal_gap 0.5)
				(thermal_bridge_width 0.5)
				(island_removal_mode 0)
			)
			(polygon
				(pts
					(xy 407.698956 -115.492784) (xy 408.968956 -115.492784) (xy 408.968956 -116.254784) (xy 407.698956 -116.254784)
				)
			)
		)
	)
	(footprint ""
		(layer "B.Cu")
		(at 390.13765 -113.45545)
		(property "Reference" "C2M22"
			(at 0 0 0)
			(layer "B.SilkS")
			(hide yes)
			(effects
				(font
					(size 1.27 1.27)
				)
				(justify mirror)
			)
		)
		(property "Value" ""
			(at 0 0 0)
			(layer "B.Fab")
			(effects
				(font
					(size 1.27 1.27)
				)
				(justify mirror)
			)
		)
		(duplicate_pad_numbers_are_jumpers no)
		(fp_rect
			(start 0.2794 0.9144)
			(end -0.2794 -0.1143)
			(stroke
				(width 0)
				(type default)
			)
			(fill no)
			(layer "B.CrtYd")
		)
		(fp_line
			(start -0.2794 -0.1143)
			(end -0.2794 0.9144)
			(stroke
				(width 0.1)
				(type default)
			)
			(layer "B.Fab")
		)
		(fp_line
			(start -0.2794 0.9144)
			(end 0.2794 0.9144)
			(stroke
				(width 0.1)
				(type default)
			)
			(layer "B.Fab")
		)
		(fp_line
			(start 0.2794 -0.1143)
			(end -0.2794 -0.1143)
			(stroke
				(width 0.1)
				(type default)
			)
			(layer "B.Fab")
		)
		(fp_line
			(start 0.2794 0.9144)
			(end 0.2794 -0.1143)
			(stroke
				(width 0.1)
				(type default)
			)
			(layer "B.Fab")
		)
		(pad "1" smd custom
			(at 0 0 270)
			(size 0.10414 0.10414)
			(layers "B.Cu" "B.Mask" "B.Paste")
			(net "P1V05_PCH_STBY")
			(options
				(clearance outline)
				(anchor circle)
			)
			(primitives
				(gr_poly
					(pts
						(xy -0.20828 -0.08636) (xy -0.20828 0.08636) (xy -0.08636 0.20828) (xy 0.086614 0.20828) (xy 0.20828 0.086614)
						(xy 0.20828 -0.08636) (xy 0.08636 -0.20828) (xy -0.08636 -0.20828)
					)
					(width 0)
					(fill yes)
				)
			)
		)
		(pad "2" smd custom
			(at 0 0.8001 270)
			(size 0.10414 0.10414)
			(layers "B.Cu" "B.Mask" "B.Paste")
			(net "GND")
			(options
				(clearance outline)
				(anchor circle)
			)
			(primitives
				(gr_poly
					(pts
						(xy -0.20828 -0.08636) (xy -0.20828 0.08636) (xy -0.08636 0.20828) (xy 0.086614 0.20828) (xy 0.20828 0.086614)
						(xy 0.20828 -0.08636) (xy 0.08636 -0.20828) (xy -0.08636 -0.20828)
					)
					(width 0)
					(fill yes)
				)
			)
		)
		(zone
			(layer "B.Cu")
			(hatch none 0.5)
			(connect_pads
				(clearance 0)
			)
			(min_thickness 0.25)
			(keepout
				(tracks allowed)
				(vias not_allowed)
				(pads allowed)
				(copperpour not_allowed)
				(footprints allowed)
			)
			(placement
				(enabled no)
				(sheetname "")
			)
			(fill
				(thermal_gap 0.5)
				(thermal_bridge_width 0.5)
				(island_removal_mode 0)
			)
			(polygon
				(pts
					(xy 390.22528 -113.2459) (xy 390.22528 -112.8649) (xy 390.05002 -112.8649) (xy 390.049766 -113.2459)
				)
			)
		)
		(zone
			(layer "B.Cu")
			(hatch none 0.5)
			(connect_pads
				(clearance 0)
			)
			(min_thickness 0.25)
			(keepout
				(tracks not_allowed)
				(vias allowed)
				(pads allowed)
				(copperpour not_allowed)
				(footprints allowed)
			)
			(placement
				(enabled no)
				(sheetname "")
			)
			(fill
				(thermal_gap 0.5)
				(thermal_bridge_width 0.5)
				(island_removal_mode 0)
			)
			(polygon
				(pts
					(xy 390.22528 -113.2459) (xy 390.22528 -112.8649) (xy 390.05002 -112.8649) (xy 390.049766 -113.2459)
				)
			)
		)
	)
	(footprint ""
		(layer "B.Cu")
		(at 351.93732 -83.510628 -90)
		(property "Reference" "R3P22"
			(at 0 0 90)
			(layer "B.SilkS")
			(hide yes)
			(effects
				(font
					(size 1.27 1.27)
				)
				(justify mirror)
			)
		)
		(property "Value" ""
			(at 0 0 90)
			(layer "B.Fab")
			(effects
				(font
					(size 1.27 1.27)
				)
				(justify mirror)
			)
		)
		(duplicate_pad_numbers_are_jumpers no)
		(fp_poly
			(pts
				(xy 0.2794 -0.1016) (xy -0.2794 -0.1016) (xy -0.2794 0.9906) (xy 0.2794 0.9906)
			)
			(stroke
				(width 0)
				(type default)
			)
			(fill no)
			(layer "B.CrtYd")
		)
		(fp_line
			(start -0.2794 0.9906)
			(end -0.2794 -0.1016)
			(stroke
				(width 0.1)
				(type default)
			)
			(layer "B.Fab")
		)
		(fp_line
			(start 0.2794 0.9906)
			(end -0.2794 0.9906)
			(stroke
				(width 0.1)
				(type default)
			)
			(layer "B.Fab")
		)
		(fp_line
			(start -0.2794 -0.1016)
			(end 0.2794 -0.1016)
			(stroke
				(width 0.1)
				(type default)
			)
			(layer "B.Fab")
		)
		(fp_line
			(start 0.2794 -0.1016)
			(end 0.2794 0.9906)
			(stroke
				(width 0.1)
				(type default)
			)
			(layer "B.Fab")
		)
		(pad "1" smd rect
			(at 0 0 90)
			(size 0.508 0.508)
			(layers "B.Cu" "B.Mask" "B.Paste")
			(net "P3V3_STBY")
		)
		(pad "2" smd rect
			(at 0 0.889 90)
			(size 0.508 0.508)
			(layers "B.Cu" "B.Mask" "B.Paste")
			(net "VR_PVCCIO_CPU0_VDD")
		)
		(zone
			(layer "B.Cu")
			(hatch none 0.5)
			(connect_pads
				(clearance 0)
			)
			(min_thickness 0.25)
			(keepout
				(tracks not_allowed)
				(vias allowed)
				(pads allowed)
				(copperpour not_allowed)
				(footprints allowed)
			)
			(placement
				(enabled no)
				(sheetname "")
			)
			(fill
				(thermal_gap 0.5)
				(thermal_bridge_width 0.5)
				(island_removal_mode 0)
			)
			(polygon
				(pts
					(xy 351.30232 -83.256628) (xy 351.30232 -83.764628) (xy 351.68332 -83.764628) (xy 351.68332 -83.256628)
				)
			)
		)
		(zone
			(layer "B.Cu")
			(hatch none 0.5)
			(connect_pads
				(clearance 0)
			)
			(min_thickness 0.25)
			(keepout
				(tracks allowed)
				(vias not_allowed)
				(pads allowed)
				(copperpour not_allowed)
				(footprints allowed)
			)
			(placement
				(enabled no)
				(sheetname "")
			)
			(fill
				(thermal_gap 0.5)
				(thermal_bridge_width 0.5)
				(island_removal_mode 0)
			)
			(polygon
				(pts
					(xy 351.68332 -83.256628) (xy 351.68332 -83.764628) (xy 351.30232 -83.764628) (xy 351.30232 -83.256628)
				)
			)
		)
	)
	(footprint ""
		(layer "B.Cu")
		(at 453.8218 -19.7993 180)
		(property "Reference" "C3W2"
			(at 0.8382 -0.67818 180)
			(unlocked yes)
			(layer "B.SilkS")
			(effects
				(font
					(size 0.4064 0.254)
					(thickness 0.1524)
				)
				(justify left mirror)
			)
		)
		(property "Value" ""
			(at 0 0 0)
			(layer "B.Fab")
			(effects
				(font
					(size 1.27 1.27)
				)
				(justify mirror)
			)
		)
		(duplicate_pad_numbers_are_jumpers no)
		(fp_poly
			(pts
				(xy -0.3048 -0.1016) (xy -0.3048 0.9906) (xy 0.3048 0.9906) (xy 0.3048 -0.1016)
			)
			(stroke
				(width 0)
				(type default)
			)
			(fill no)
			(layer "B.CrtYd")
		)
		(fp_line
			(start 0.3048 0.9906)
			(end -0.3048 0.9906)
			(stroke
				(width 0.1)
				(type default)
			)
			(layer "B.Fab")
		)
		(fp_line
			(start 0.3048 -0.1016)
			(end 0.3048 0.9906)
			(stroke
				(width 0.1)
				(type default)
			)
			(layer "B.Fab")
		)
		(fp_line
			(start -0.3048 0.9906)
			(end -0.3048 -0.1016)
			(stroke
				(width 0.1)
				(type default)
			)
			(layer "B.Fab")
		)
		(fp_line
			(start -0.3048 -0.1016)
			(end 0.3048 -0.1016)
			(stroke
				(width 0.1)
				(type default)
			)
			(layer "B.Fab")
		)
		(pad "1" smd rect
			(at 0 0)
			(size 0.508 0.508)
			(layers "B.Cu" "B.Mask" "B.Paste")
			(net "BMC_TPM_HW_C_RST")
		)
		(pad "2" smd rect
			(at 0 0.889)
			(size 0.508 0.508)
			(layers "B.Cu" "B.Mask" "B.Paste")
			(net "GND")
		)
		(zone
			(layer "B.Cu")
			(hatch none 0.5)
			(connect_pads
				(clearance 0)
			)
			(min_thickness 0.25)
			(keepout
				(tracks not_allowed)
				(vias allowed)
				(pads allowed)
				(copperpour not_allowed)
				(footprints allowed)
			)
			(placement
				(enabled no)
				(sheetname "")
			)
			(fill
				(thermal_gap 0.5)
				(thermal_bridge_width 0.5)
				(island_removal_mode 0)
			)
			(polygon
				(pts
					(xy 453.5678 -20.4343) (xy 454.0758 -20.4343) (xy 454.0758 -20.0533) (xy 453.5678 -20.0533)
				)
			)
		)
		(zone
			(layer "B.Cu")
			(hatch none 0.5)
			(connect_pads
				(clearance 0)
			)
			(min_thickness 0.25)
			(keepout
				(tracks allowed)
				(vias not_allowed)
				(pads allowed)
				(copperpour not_allowed)
				(footprints allowed)
			)
			(placement
				(enabled no)
				(sheetname "")
			)
			(fill
				(thermal_gap 0.5)
				(thermal_bridge_width 0.5)
				(island_removal_mode 0)
			)
			(polygon
				(pts
					(xy 453.5678 -20.0533) (xy 454.0758 -20.0533) (xy 454.0758 -20.4343) (xy 453.5678 -20.4343)
				)
			)
		)
	)
	(footprint ""
		(layer "B.Cu")
		(at 416.9664 -22.225)
		(property "Reference" "R25W123"
			(at 0.8382 -0.67818 0)
			(unlocked yes)
			(layer "B.SilkS")
			(effects
				(font
					(size 0.4064 0.254)
					(thickness 0.1524)
				)
				(justify left mirror)
			)
		)
		(property "Value" ""
			(at 0 0 0)
			(layer "B.Fab")
			(effects
				(font
					(size 1.27 1.27)
				)
				(justify mirror)
			)
		)
		(duplicate_pad_numbers_are_jumpers no)
		(fp_poly
			(pts
				(xy 0.2794 -0.1016) (xy -0.2794 -0.1016) (xy -0.2794 0.9906) (xy 0.2794 0.9906)
			)
			(stroke
				(width 0)
				(type default)
			)
			(fill no)
			(layer "B.CrtYd")
		)
		(fp_line
			(start -0.2794 -0.1016)
			(end 0.2794 -0.1016)
			(stroke
				(width 0.1)
				(type default)
			)
			(layer "B.Fab")
		)
		(fp_line
			(start -0.2794 0.9906)
			(end -0.2794 -0.1016)
			(stroke
				(width 0.1)
				(type default)
			)
			(layer "B.Fab")
		)
		(fp_line
			(start 0.2794 -0.1016)
			(end 0.2794 0.9906)
			(stroke
				(width 0.1)
				(type default)
			)
			(layer "B.Fab")
		)
		(fp_line
			(start 0.2794 0.9906)
			(end -0.2794 0.9906)
			(stroke
				(width 0.1)
				(type default)
			)
			(layer "B.Fab")
		)
		(pad "1" smd rect
			(at 0 0 180)
			(size 0.508 0.508)
			(layers "B.Cu" "B.Mask" "B.Paste")
			(net "BMC_VGA_BLUE")
		)
		(pad "2" smd rect
			(at 0 0.889 180)
			(size 0.508 0.508)
			(layers "B.Cu" "B.Mask" "B.Paste")
			(net "GND")
		)
		(zone
			(layer "B.Cu")
			(hatch none 0.5)
			(connect_pads
				(clearance 0)
			)
			(min_thickness 0.25)
			(keepout
				(tracks allowed)
				(vias not_allowed)
				(pads allowed)
				(copperpour not_allowed)
				(footprints allowed)
			)
			(placement
				(enabled no)
				(sheetname "")
			)
			(fill
				(thermal_gap 0.5)
				(thermal_bridge_width 0.5)
				(island_removal_mode 0)
			)
			(polygon
				(pts
					(xy 417.2204 -21.971) (xy 416.7124 -21.971) (xy 416.7124 -21.59) (xy 417.2204 -21.59)
				)
			)
		)
		(zone
			(layer "B.Cu")
			(hatch none 0.5)
			(connect_pads
				(clearance 0)
			)
			(min_thickness 0.25)
			(keepout
				(tracks not_allowed)
				(vias allowed)
				(pads allowed)
				(copperpour not_allowed)
				(footprints allowed)
			)
			(placement
				(enabled no)
				(sheetname "")
			)
			(fill
				(thermal_gap 0.5)
				(thermal_bridge_width 0.5)
				(island_removal_mode 0)
			)
			(polygon
				(pts
					(xy 417.2204 -21.59) (xy 416.7124 -21.59) (xy 416.7124 -21.971) (xy 417.2204 -21.971)
				)
			)
		)
	)
	(footprint ""
		(layer "B.Cu")
		(at 416.179 -26.035)
		(property "Reference" "C25W74"
			(at 0.8382 -0.67818 0)
			(unlocked yes)
			(layer "B.SilkS")
			(effects
				(font
					(size 0.4064 0.254)
					(thickness 0.1524)
				)
				(justify left mirror)
			)
		)
		(property "Value" ""
			(at 0 0 0)
			(layer "B.Fab")
			(effects
				(font
					(size 1.27 1.27)
				)
				(justify mirror)
			)
		)
		(duplicate_pad_numbers_are_jumpers no)
		(fp_poly
			(pts
				(xy -0.3048 -0.1016) (xy -0.3048 0.9906) (xy 0.3048 0.9906) (xy 0.3048 -0.1016)
			)
			(stroke
				(width 0)
				(type default)
			)
			(fill no)
			(layer "B.CrtYd")
		)
		(fp_line
			(start -0.3048 -0.1016)
			(end 0.3048 -0.1016)
			(stroke
				(width 0.1)
				(type default)
			)
			(layer "B.Fab")
		)
		(fp_line
			(start -0.3048 0.9906)
			(end -0.3048 -0.1016)
			(stroke
				(width 0.1)
				(type default)
			)
			(layer "B.Fab")
		)
		(fp_line
			(start 0.3048 -0.1016)
			(end 0.3048 0.9906)
			(stroke
				(width 0.1)
				(type default)
			)
			(layer "B.Fab")
		)
		(fp_line
			(start 0.3048 0.9906)
			(end -0.3048 0.9906)
			(stroke
				(width 0.1)
				(type default)
			)
			(layer "B.Fab")
		)
		(pad "1" smd rect
			(at 0 0 180)
			(size 0.508 0.508)
			(layers "B.Cu" "B.Mask" "B.Paste")
			(net "BMC_VGA_RED")
		)
		(pad "2" smd rect
			(at 0 0.889 180)
			(size 0.508 0.508)
			(layers "B.Cu" "B.Mask" "B.Paste")
			(net "GND")
		)
		(zone
			(layer "B.Cu")
			(hatch none 0.5)
			(connect_pads
				(clearance 0)
			)
			(min_thickness 0.25)
			(keepout
				(tracks allowed)
				(vias not_allowed)
				(pads allowed)
				(copperpour not_allowed)
				(footprints allowed)
			)
			(placement
				(enabled no)
				(sheetname "")
			)
			(fill
				(thermal_gap 0.5)
				(thermal_bridge_width 0.5)
				(island_removal_mode 0)
			)
			(polygon
				(pts
					(xy 416.433 -25.781) (xy 415.925 -25.781) (xy 415.925 -25.4) (xy 416.433 -25.4)
				)
			)
		)
		(zone
			(layer "B.Cu")
			(hatch none 0.5)
			(connect_pads
				(clearance 0)
			)
			(min_thickness 0.25)
			(keepout
				(tracks not_allowed)
				(vias allowed)
				(pads allowed)
				(copperpour not_allowed)
				(footprints allowed)
			)
			(placement
				(enabled no)
				(sheetname "")
			)
			(fill
				(thermal_gap 0.5)
				(thermal_bridge_width 0.5)
				(island_removal_mode 0)
			)
			(polygon
				(pts
					(xy 416.433 -25.4) (xy 415.925 -25.4) (xy 415.925 -25.781) (xy 416.433 -25.781)
				)
			)
		)
	)
	(footprint ""
		(layer "B.Cu")
		(at 463.8294 -52.432458)
		(property "Reference" "C1R1"
			(at 0 0 0)
			(layer "B.SilkS")
			(hide yes)
			(effects
				(font
					(size 1.27 1.27)
				)
				(justify mirror)
			)
		)
		(property "Value" ""
			(at 0 0 0)
			(layer "B.Fab")
			(effects
				(font
					(size 1.27 1.27)
				)
				(justify mirror)
			)
		)
		(duplicate_pad_numbers_are_jumpers no)
		(fp_poly
			(pts
				(xy -0.3048 -0.1016) (xy -0.3048 0.9906) (xy 0.3048 0.9906) (xy 0.3048 -0.1016)
			)
			(stroke
				(width 0)
				(type default)
			)
			(fill no)
			(layer "B.CrtYd")
		)
		(fp_line
			(start -0.3048 -0.1016)
			(end 0.3048 -0.1016)
			(stroke
				(width 0.1)
				(type default)
			)
			(layer "B.Fab")
		)
		(fp_line
			(start -0.3048 0.9906)
			(end -0.3048 -0.1016)
			(stroke
				(width 0.1)
				(type default)
			)
			(layer "B.Fab")
		)
		(fp_line
			(start 0.3048 -0.1016)
			(end 0.3048 0.9906)
			(stroke
				(width 0.1)
				(type default)
			)
			(layer "B.Fab")
		)
		(fp_line
			(start 0.3048 0.9906)
			(end -0.3048 0.9906)
			(stroke
				(width 0.1)
				(type default)
			)
			(layer "B.Fab")
		)
		(pad "1" smd rect
			(at 0 0 180)
			(size 0.508 0.508)
			(layers "B.Cu" "B.Mask" "B.Paste")
			(net "P3E_CPU0_PE3_OCP_TXN<0>")
		)
		(pad "2" smd rect
			(at 0 0.889 180)
			(size 0.508 0.508)
			(layers "B.Cu" "B.Mask" "B.Paste")
			(net "P3E_OCP_CPU0_PE3_C_TXN<0>")
		)
		(zone
			(layer "B.Cu")
			(hatch none 0.5)
			(connect_pads
				(clearance 0)
			)
			(min_thickness 0.25)
			(keepout
				(tracks allowed)
				(vias not_allowed)
				(pads allowed)
				(copperpour not_allowed)
				(footprints allowed)
			)
			(placement
				(enabled no)
				(sheetname "")
			)
			(fill
				(thermal_gap 0.5)
				(thermal_bridge_width 0.5)
				(island_removal_mode 0)
			)
			(polygon
				(pts
					(xy 464.0834 -52.178458) (xy 463.5754 -52.178458) (xy 463.5754 -51.797458) (xy 464.0834 -51.797458)
				)
			)
		)
		(zone
			(layer "B.Cu")
			(hatch none 0.5)
			(connect_pads
				(clearance 0)
			)
			(min_thickness 0.25)
			(keepout
				(tracks not_allowed)
				(vias allowed)
				(pads allowed)
				(copperpour not_allowed)
				(footprints allowed)
			)
			(placement
				(enabled no)
				(sheetname "")
			)
			(fill
				(thermal_gap 0.5)
				(thermal_bridge_width 0.5)
				(island_removal_mode 0)
			)
			(polygon
				(pts
					(xy 464.0834 -51.797458) (xy 463.5754 -51.797458) (xy 463.5754 -52.178458) (xy 464.0834 -52.178458)
				)
			)
		)
	)
)
